# T6G (Grand Teton) — schematic netlist excerpt (pin names and nets, part order shuffled) for the footprints in the layout excerpt that follows; sources: Cadence DE-HDL packaged netlist, KiCad conversion of 04192023_DAF0TMB3IC0_F0TG_MB_C_brd_V02_OCP.brd

R1469  Q_RES  1K 1% CHIP  pkg 0201LF  page 185 : A = P1V8_CPU1_RT_1D ; B = SMB_RT_CPU1_P2_ROM_MUX_1D_SCL
R1439  Q_RES  4.7K 5% EMPTY  pkg 0201LF  page 276 : A = P1V8_CPU0_RT_1D ; B = JTAG_TMS_RT_CPU0_P0
C99  Q_CAP  0.1UF 25V 10% X7R  pkg 0402  page 183 : A = P3V3_9ZXL045_P1_VDD ; B = GND

(kicad_pcb
	(version 20260206)
	(generator "pcbnew")
	(generator_version "10.0")
	(general
		(thickness 1.6)
		(legacy_teardrops no)
	)
	(paper "A4")
	(title_block
		(title "04192023_DAF0TMB3IC0_F0TG_MB_C_brd_V02_OCP.brd")
		(comment 1 "Grand Teton / footprints 5514-5516 of 8354")
	)
	(layers
		(0 "F.Cu" signal "TOP")
		(4 "In1.Cu" signal "GND")
		(6 "In2.Cu" signal "IN1")
		(8 "In3.Cu" signal "GND1")
		(10 "In4.Cu" signal "IN2")
		(12 "In5.Cu" signal "GND2")
		(14 "In6.Cu" signal "IN3")
		(16 "In7.Cu" signal "GND3")
		(18 "In8.Cu" signal "VCC")
		(20 "In9.Cu" signal "VCC1")
		(22 "In10.Cu" signal "GND4")
		(24 "In11.Cu" signal "IN4")
		(26 "In12.Cu" signal "GND5")
		(28 "In13.Cu" signal "IN5")
		(30 "In14.Cu" signal "GND6")
		(32 "In15.Cu" signal "IN6")
		(34 "In16.Cu" signal "GND7")
		(2 "B.Cu" signal "BOTTOM")
		(9 "F.Adhes" user "F.Adhesive")
		(11 "B.Adhes" user "B.Adhesive")
		(13 "F.Paste" user "Package Geometry/Pastemask Top")
		(15 "B.Paste" user "Package Geometry/Pastemask Bottom")
		(5 "F.SilkS" user "Ref Des/Silkscreen Top")
		(7 "B.SilkS" user "Ref Des/Silkscreen Bottom")
		(1 "F.Mask" user "Board Geometry/Soldermask Top")
		(3 "B.Mask" user "Board Geometry/Soldermask Bottom")
		(17 "Dwgs.User" user "User.Drawings")
		(19 "Cmts.User" user "User.Comments")
		(21 "Eco1.User" user "User.Eco1")
		(23 "Eco2.User" user "User.Eco2")
		(25 "Edge.Cuts" user "Board Geometry/Outline")
		(27 "Margin" user)
		(31 "F.CrtYd" user "Package Geometry/Place Bound Top")
		(29 "B.CrtYd" user "Package Geometry/Place Bound Bottom")
		(35 "F.Fab" user "Ref Des/Assembly Top")
		(33 "B.Fab" user "Ref Des/Assembly Bottom")
	)
	(footprint ""
		(layer "B.Cu")
		(at 305.423316 -425.6532 180)
		(property "Reference" "R1439"
			(at 0 0 0)
			(layer "B.SilkS")
			(hide yes)
			(effects
				(font
					(size 1.27 1.27)
				)
				(justify mirror)
			)
		)
		(property "Value" ""
			(at 0 0 0)
			(layer "B.Fab")
			(effects
				(font
					(size 1.27 1.27)
				)
				(justify mirror)
			)
		)
		(duplicate_pad_numbers_are_jumpers no)
		(fp_line
			(start 0.32512 0.175006)
			(end 0.32512 -0.175006)
			(stroke
				(width 0.1)
				(type default)
			)
			(layer "B.Fab")
		)
		(fp_line
			(start 0.32512 -0.175006)
			(end -0.32512 -0.175006)
			(stroke
				(width 0.1)
				(type default)
			)
			(layer "B.Fab")
		)
		(fp_line
			(start -0.32512 0.175006)
			(end 0.32512 0.175006)
			(stroke
				(width 0.1)
				(type default)
			)
			(layer "B.Fab")
		)
		(fp_line
			(start -0.32512 -0.175006)
			(end -0.32512 0.175006)
			(stroke
				(width 0.1)
				(type default)
			)
			(layer "B.Fab")
		)
		(pad "1" smd rect
			(at 0.2667 0)
			(size 0.3048 0.381)
			(layers "B.Cu" "B.Mask" "B.Paste")
			(net "P1V8_CPU0_RT_1D")
		)
		(pad "2" smd rect
			(at -0.2667 0 180)
			(size 0.3048 0.381)
			(layers "B.Cu" "B.Mask" "B.Paste")
			(net "JTAG_TMS_RT_CPU0_P0")
		)
	)
	(footprint ""
		(layer "B.Cu")
		(at 157.226 -416.1536 180)
		(property "Reference" "R1469"
			(at 0 0 0)
			(layer "B.SilkS")
			(hide yes)
			(effects
				(font
					(size 1.27 1.27)
				)
				(justify mirror)
			)
		)
		(property "Value" ""
			(at 0 0 0)
			(layer "B.Fab")
			(effects
				(font
					(size 1.27 1.27)
				)
				(justify mirror)
			)
		)
		(duplicate_pad_numbers_are_jumpers no)
		(fp_line
			(start 0.32512 0.175006)
			(end 0.32512 -0.175006)
			(stroke
				(width 0.1)
				(type default)
			)
			(layer "B.Fab")
		)
		(fp_line
			(start 0.32512 -0.175006)
			(end -0.32512 -0.175006)
			(stroke
				(width 0.1)
				(type default)
			)
			(layer "B.Fab")
		)
		(fp_line
			(start -0.32512 0.175006)
			(end 0.32512 0.175006)
			(stroke
				(width 0.1)
				(type default)
			)
			(layer "B.Fab")
		)
		(fp_line
			(start -0.32512 -0.175006)
			(end -0.32512 0.175006)
			(stroke
				(width 0.1)
				(type default)
			)
			(layer "B.Fab")
		)
		(pad "1" smd rect
			(at 0.2667 0)
			(size 0.3048 0.381)
			(layers "B.Cu" "B.Mask" "B.Paste")
			(net "P1V8_CPU1_RT_1D")
		)
		(pad "2" smd rect
			(at -0.2667 0 180)
			(size 0.3048 0.381)
			(layers "B.Cu" "B.Mask" "B.Paste")
			(net "SMB_RT_CPU1_P2_ROM_MUX_1D_SCL")
		)
	)
	(footprint ""
		(layer "B.Cu")
		(at 104.514904 -408.980894 180)
		(property "Reference" "C99"
			(at 0 0 0)
			(layer "B.SilkS")
			(hide yes)
			(effects
				(font
					(size 1.27 1.27)
				)
				(justify mirror)
			)
		)
		(property "Value" ""
			(at 0 0 0)
			(layer "B.Fab")
			(effects
				(font
					(size 1.27 1.27)
				)
				(justify mirror)
			)
		)
		(duplicate_pad_numbers_are_jumpers no)
		(fp_line
			(start 0.7874 0.4064)
			(end 0.7874 -0.4064)
			(stroke
				(width 0.1524)
				(type default)
			)
			(layer "B.SilkS")
		)
		(fp_line
			(start 0.7874 -0.4064)
			(end -0.7874 -0.4064)
			(stroke
				(width 0.1524)
				(type default)
			)
			(layer "B.SilkS")
		)
		(fp_line
			(start -0.7874 0.4064)
			(end 0.7874 0.4064)
			(stroke
				(width 0.1524)
				(type default)
			)
			(layer "B.SilkS")
		)
		(fp_line
			(start -0.7874 -0.4064)
			(end -0.7874 0.4064)
			(stroke
				(width 0.1524)
				(type default)
			)
			(layer "B.SilkS")
		)
		(fp_line
			(start 0.67945 0.3048)
			(end 0.67945 -0.305054)
			(stroke
				(width 0.1)
				(type default)
			)
			(layer "B.Fab")
		)
		(fp_line
			(start 0.67945 -0.305054)
			(end 0.12065 -0.305054)
			(stroke
				(width 0.1)
				(type default)
			)
			(layer "B.Fab")
		)
		(fp_line
			(start 0.12065 0.3048)
			(end 0.67945 0.3048)
			(stroke
				(width 0.1)
				(type default)
			)
			(layer "B.Fab")
		)
		(fp_line
			(start 0.12065 0.2794)
			(end 0.12065 0.3048)
			(stroke
				(width 0.1)
				(type default)
			)
			(layer "B.Fab")
		)
		(fp_line
			(start 0.12065 -0.2794)
			(end -0.12065 -0.2794)
			(stroke
				(width 0.1)
				(type default)
			)
			(layer "B.Fab")
		)
		(fp_line
			(start 0.12065 -0.305054)
			(end 0.12065 -0.2794)
			(stroke
				(width 0.1)
				(type default)
			)
			(layer "B.Fab")
		)
		(fp_line
			(start -0.120396 0.3048)
			(end -0.120396 0.2794)
			(stroke
				(width 0.1)
				(type default)
			)
			(layer "B.Fab")
		)
		(fp_line
			(start -0.120396 0.2794)
			(end 0.12065 0.2794)
			(stroke
				(width 0.1)
				(type default)
			)
			(layer "B.Fab")
		)
		(fp_line
			(start -0.12065 -0.2794)
			(end -0.12065 -0.3048)
			(stroke
				(width 0.1)
				(type default)
			)
			(layer "B.Fab")
		)
		(fp_line
			(start -0.12065 -0.3048)
			(end -0.67945 -0.3048)
			(stroke
				(width 0.1)
				(type default)
			)
			(layer "B.Fab")
		)
		(fp_line
			(start -0.67945 0.3048)
			(end -0.120396 0.3048)
			(stroke
				(width 0.1)
				(type default)
			)
			(layer "B.Fab")
		)
		(fp_line
			(start -0.67945 -0.3048)
			(end -0.67945 0.3048)
			(stroke
				(width 0.1)
				(type default)
			)
			(layer "B.Fab")
		)
		(pad "1" smd circle
			(at 0.40005 0)
			(size 0 0)
			(layers "B.Cu" "B.Mask" "B.Paste")
			(net "P3V3_9ZXL045_P1_VDD")
		)
		(pad "2" smd circle
			(at -0.40005 0)
			(size 0 0)
			(layers "B.Cu" "B.Mask" "B.Paste")
			(net "GND")
		)
	)
)
